# T6G (Grand Teton) — schematic netlist excerpt (pin names and nets, part order shuffled) for the footprints in the layout excerpt that follows; sources: Cadence DE-HDL packaged netlist, KiCad conversion of 04192023_DAF0TMB3IC0_F0TG_MB_C_brd_V02_OCP.brd

C891  Q_CAP_DIFFBUS  DIFF BUS_0.22UF 6.3V 20% X6S  pkg C0201  page 64 : \1\ = P5E_CPU0_P3_TX_C_DP<5> ; \2\ = P5E_CPU0_P3_TX_DP<5>
PC6801  Q_CAPP  270UF 16V 20% OSCON  pkg SMLF  page 361 : A = SW_P12V_AUX_P1V8_RETIMER_CPU1_FLT ; B = GND
C6572  Q_CAP_DIFFBUS  DIFF BUS_0.22UF 6.3V 20% X6S  pkg C0201  page 297 : \1\ = P5E_CPU0_P2_TX_BUF_C_DN<3> ; \2\ = P5E_CPU0_P2_TX_BUF_DN<3>
PC260_1  Q_CAP  0.1UF 25V 10% X7R  pkg 0402  page 211 : A = SW_P12V_AUX_PVDDCR_CPU0_P1_FLT ; B = GND

(kicad_pcb
	(version 20260206)
	(generator "pcbnew")
	(generator_version "10.0")
	(general
		(thickness 1.6)
		(legacy_teardrops no)
	)
	(paper "A4")
	(title_block
		(title "04192023_DAF0TMB3IC0_F0TG_MB_C_brd_V02_OCP.brd")
		(comment 1 "Grand Teton / footprints 3228-3231 of 8354")
	)
	(layers
		(0 "F.Cu" signal "TOP")
		(4 "In1.Cu" signal "GND")
		(6 "In2.Cu" signal "IN1")
		(8 "In3.Cu" signal "GND1")
		(10 "In4.Cu" signal "IN2")
		(12 "In5.Cu" signal "GND2")
		(14 "In6.Cu" signal "IN3")
		(16 "In7.Cu" signal "GND3")
		(18 "In8.Cu" signal "VCC")
		(20 "In9.Cu" signal "VCC1")
		(22 "In10.Cu" signal "GND4")
		(24 "In11.Cu" signal "IN4")
		(26 "In12.Cu" signal "GND5")
		(28 "In13.Cu" signal "IN5")
		(30 "In14.Cu" signal "GND6")
		(32 "In15.Cu" signal "IN6")
		(34 "In16.Cu" signal "GND7")
		(2 "B.Cu" signal "BOTTOM")
		(9 "F.Adhes" user "F.Adhesive")
		(11 "B.Adhes" user "B.Adhesive")
		(13 "F.Paste" user "Package Geometry/Pastemask Top")
		(15 "B.Paste" user "Package Geometry/Pastemask Bottom")
		(5 "F.SilkS" user "Ref Des/Silkscreen Top")
		(7 "B.SilkS" user "Ref Des/Silkscreen Bottom")
		(1 "F.Mask" user "Board Geometry/Soldermask Top")
		(3 "B.Mask" user "Board Geometry/Soldermask Bottom")
		(17 "Dwgs.User" user "User.Drawings")
		(19 "Cmts.User" user "User.Comments")
		(21 "Eco1.User" user "User.Eco1")
		(23 "Eco2.User" user "User.Eco2")
		(25 "Edge.Cuts" user "Board Geometry/Outline")
		(27 "Margin" user)
		(31 "F.CrtYd" user "Package Geometry/Place Bound Top")
		(29 "B.CrtYd" user "Package Geometry/Place Bound Bottom")
		(35 "F.Fab" user "Ref Des/Assembly Top")
		(33 "B.Fab" user "Ref Des/Assembly Bottom")
	)
	(footprint ""
		(layer "F.Cu")
		(at 80.173322 -176.40935)
		(property "Reference" "PC260_1"
			(at 0 0 0)
			(layer "F.SilkS")
			(hide yes)
			(effects
				(font
					(size 1.27 1.27)
				)
			)
		)
		(property "Value" ""
			(at 0 0 0)
			(layer "F.Fab")
			(effects
				(font
					(size 1.27 1.27)
				)
			)
		)
		(duplicate_pad_numbers_are_jumpers no)
		(fp_line
			(start -0.7874 -0.4064)
			(end 0.7874 -0.4064)
			(stroke
				(width 0.1524)
				(type default)
			)
			(layer "F.SilkS")
		)
		(fp_line
			(start -0.7874 0.4064)
			(end -0.7874 -0.4064)
			(stroke
				(width 0.1524)
				(type default)
			)
			(layer "F.SilkS")
		)
		(fp_line
			(start 0.7874 -0.4064)
			(end 0.7874 0.4064)
			(stroke
				(width 0.1524)
				(type default)
			)
			(layer "F.SilkS")
		)
		(fp_line
			(start 0.7874 0.4064)
			(end -0.7874 0.4064)
			(stroke
				(width 0.1524)
				(type default)
			)
			(layer "F.SilkS")
		)
		(fp_line
			(start -0.67945 -0.305054)
			(end -0.12065 -0.305054)
			(stroke
				(width 0.1)
				(type default)
			)
			(layer "F.Fab")
		)
		(fp_line
			(start -0.67945 0.3048)
			(end -0.67945 -0.305054)
			(stroke
				(width 0.1)
				(type default)
			)
			(layer "F.Fab")
		)
		(fp_line
			(start -0.12065 -0.305054)
			(end -0.12065 -0.2794)
			(stroke
				(width 0.1)
				(type default)
			)
			(layer "F.Fab")
		)
		(fp_line
			(start -0.12065 -0.2794)
			(end 0.12065 -0.2794)
			(stroke
				(width 0.1)
				(type default)
			)
			(layer "F.Fab")
		)
		(fp_line
			(start -0.12065 0.2794)
			(end -0.12065 0.3048)
			(stroke
				(width 0.1)
				(type default)
			)
			(layer "F.Fab")
		)
		(fp_line
			(start -0.12065 0.3048)
			(end -0.67945 0.3048)
			(stroke
				(width 0.1)
				(type default)
			)
			(layer "F.Fab")
		)
		(fp_line
			(start 0.120396 0.2794)
			(end -0.12065 0.2794)
			(stroke
				(width 0.1)
				(type default)
			)
			(layer "F.Fab")
		)
		(fp_line
			(start 0.120396 0.3048)
			(end 0.120396 0.2794)
			(stroke
				(width 0.1)
				(type default)
			)
			(layer "F.Fab")
		)
		(fp_line
			(start 0.12065 -0.3048)
			(end 0.67945 -0.3048)
			(stroke
				(width 0.1)
				(type default)
			)
			(layer "F.Fab")
		)
		(fp_line
			(start 0.12065 -0.2794)
			(end 0.12065 -0.3048)
			(stroke
				(width 0.1)
				(type default)
			)
			(layer "F.Fab")
		)
		(fp_line
			(start 0.67945 -0.3048)
			(end 0.67945 0.3048)
			(stroke
				(width 0.1)
				(type default)
			)
			(layer "F.Fab")
		)
		(fp_line
			(start 0.67945 0.3048)
			(end 0.120396 0.3048)
			(stroke
				(width 0.1)
				(type default)
			)
			(layer "F.Fab")
		)
		(pad "1" smd circle
			(at -0.40005 0)
			(size 0 0)
			(layers "F.Cu" "F.Mask" "F.Paste")
			(net "SW_P12V_AUX_PVDDCR_CPU0_P1_FLT")
		)
		(pad "2" smd circle
			(at 0.40005 0)
			(size 0 0)
			(layers "F.Cu" "F.Mask" "F.Paste")
			(net "GND")
		)
	)
	(footprint ""
		(layer "F.Cu")
		(at 380.058422 -416.899344 -90)
		(property "Reference" "C6572"
			(at 0 0 270)
			(layer "F.SilkS")
			(hide yes)
			(effects
				(font
					(size 1.27 1.27)
				)
			)
		)
		(property "Value" ""
			(at 0 0 270)
			(layer "F.Fab")
			(effects
				(font
					(size 1.27 1.27)
				)
			)
		)
		(duplicate_pad_numbers_are_jumpers no)
		(fp_line
			(start -0.299974 0.150114)
			(end -0.299974 -0.150114)
			(stroke
				(width 0.1)
				(type default)
			)
			(layer "F.Fab")
		)
		(fp_line
			(start 0.299974 0.150114)
			(end -0.299974 0.150114)
			(stroke
				(width 0.1)
				(type default)
			)
			(layer "F.Fab")
		)
		(fp_line
			(start -0.299974 -0.150114)
			(end 0.299974 -0.150114)
			(stroke
				(width 0.1)
				(type default)
			)
			(layer "F.Fab")
		)
		(fp_line
			(start 0.299974 -0.150114)
			(end 0.299974 0.150114)
			(stroke
				(width 0.1)
				(type default)
			)
			(layer "F.Fab")
		)
		(pad "1" smd rect
			(at -0.2667 0 270)
			(size 0.3048 0.381)
			(layers "F.Cu" "F.Mask" "F.Paste")
			(net "P5E_CPU0_P2_TX_BUF_C_DN<3>")
		)
		(pad "2" smd rect
			(at 0.2667 0 270)
			(size 0.3048 0.381)
			(layers "F.Cu" "F.Mask" "F.Paste")
			(net "P5E_CPU0_P2_TX_BUF_DN<3>")
		)
	)
	(footprint ""
		(layer "F.Cu")
		(at 372.896892 -381.41783 -90)
		(property "Reference" "C891"
			(at 0 0 270)
			(layer "F.SilkS")
			(hide yes)
			(effects
				(font
					(size 1.27 1.27)
				)
			)
		)
		(property "Value" ""
			(at 0 0 270)
			(layer "F.Fab")
			(effects
				(font
					(size 1.27 1.27)
				)
			)
		)
		(duplicate_pad_numbers_are_jumpers no)
		(fp_line
			(start -0.299974 0.150114)
			(end -0.299974 -0.150114)
			(stroke
				(width 0.1)
				(type default)
			)
			(layer "F.Fab")
		)
		(fp_line
			(start 0.299974 0.150114)
			(end -0.299974 0.150114)
			(stroke
				(width 0.1)
				(type default)
			)
			(layer "F.Fab")
		)
		(fp_line
			(start -0.299974 -0.150114)
			(end 0.299974 -0.150114)
			(stroke
				(width 0.1)
				(type default)
			)
			(layer "F.Fab")
		)
		(fp_line
			(start 0.299974 -0.150114)
			(end 0.299974 0.150114)
			(stroke
				(width 0.1)
				(type default)
			)
			(layer "F.Fab")
		)
		(pad "1" smd rect
			(at -0.2667 0 270)
			(size 0.3048 0.381)
			(layers "F.Cu" "F.Mask" "F.Paste")
			(net "P5E_CPU0_P3_TX_C_DP<5>")
		)
		(pad "2" smd rect
			(at 0.2667 0 270)
			(size 0.3048 0.381)
			(layers "F.Cu" "F.Mask" "F.Paste")
			(net "P5E_CPU0_P3_TX_DP<5>")
		)
	)
	(footprint ""
		(layer "F.Cu")
		(at 225.228912 -277.572978 180)
		(property "Reference" "PC6801"
			(at 3.359912 4.213352 0)
			(unlocked yes)
			(layer "F.SilkS")
			(effects
				(font
					(size 0.7874 0.5842)
					(thickness 0.1524)
				)
				(justify left)
			)
		)
		(property "Value" ""
			(at 0 0 180)
			(layer "F.Fab")
			(effects
				(font
					(size 1.27 1.27)
				)
			)
		)
		(duplicate_pad_numbers_are_jumpers no)
		(fp_line
			(start 3.400044 3.400044)
			(end -2.146046 3.400044)
			(stroke
				(width 0.1524)
				(type default)
			)
			(layer "F.SilkS")
		)
		(fp_line
			(start 3.400044 0.9398)
			(end 3.400044 3.400044)
			(stroke
				(width 0.1524)
				(type default)
			)
			(layer "F.SilkS")
		)
		(fp_line
			(start 3.400044 -0.9398)
			(end 3.400044 -3.400044)
			(stroke
				(width 0.1524)
				(type default)
			)
			(layer "F.SilkS")
		)
		(fp_line
			(start 3.400044 -3.400044)
			(end -2.146046 -3.400044)
			(stroke
				(width 0.1524)
				(type default)
			)
			(layer "F.SilkS")
		)
		(fp_line
			(start -2.146046 3.400044)
			(end -3.400044 2.146046)
			(stroke
				(width 0.1524)
				(type default)
			)
			(layer "F.SilkS")
		)
		(fp_line
			(start -2.146046 -3.400044)
			(end -3.400044 -2.146046)
			(stroke
				(width 0.1524)
				(type default)
			)
			(layer "F.SilkS")
		)
		(fp_line
			(start -3.400044 2.146046)
			(end -3.400044 0.9398)
			(stroke
				(width 0.1524)
				(type default)
			)
			(layer "F.SilkS")
		)
		(fp_line
			(start -3.400044 -2.146046)
			(end -3.400044 -0.9398)
			(stroke
				(width 0.1524)
				(type default)
			)
			(layer "F.SilkS")
		)
		(fp_line
			(start 3.400044 3.400044)
			(end 3.400044 -3.400044)
			(stroke
				(width 0.1)
				(type default)
			)
			(layer "F.Fab")
		)
		(fp_line
			(start 3.400044 -3.400044)
			(end -3.400044 -3.400044)
			(stroke
				(width 0.1)
				(type default)
			)
			(layer "F.Fab")
		)
		(fp_line
			(start -3.400044 3.400044)
			(end 3.400044 3.400044)
			(stroke
				(width 0.1)
				(type default)
			)
			(layer "F.Fab")
		)
		(fp_line
			(start -3.400044 -3.400044)
			(end -3.400044 3.400044)
			(stroke
				(width 0.1)
				(type default)
			)
			(layer "F.Fab")
		)
		(pad "1" smd rect
			(at -2.70002 0 90)
			(size 1.6002 3.5052)
			(layers "F.Cu" "F.Mask" "F.Paste")
			(net "SW_P12V_AUX_P1V8_RETIMER_CPU1_FLT")
		)
		(pad "2" smd rect
			(at 2.70002 0 90)
			(size 1.6002 3.5052)
			(layers "F.Cu" "F.Mask" "F.Paste")
			(net "GND")
		)
	)
)
